# T6G (Grand Teton) — schematic netlist excerpt (pin names and nets, part order shuffled) for the footprints in the layout excerpt that follows; sources: Cadence DE-HDL packaged netlist, KiCad conversion of 04192023_DAF0TMB3IC0_F0TG_MB_C_brd_V02_OCP.brd

PR69  Q_RES  0 5% CHIP  pkg 0402LF  page 200 : A = VSENSE_PVDDIO_P0_DP ; B = VSENSE_PVDDIO_P0_VSEN1

U196  74LVC2G17GW  IC  pkg SOT363  page 130
  A0  = FM_GPU_PWR_EN_R
  GND  = GND
  A1  = GPU_FPGA_RST_R_N
  B1  = GPU_FPGA_RST_R1_BUF_N
  VCC  = P3V3_AUX
  B0  = FM_GPU_PWR_EN_R1

(kicad_pcb
	(version 20260206)
	(generator "pcbnew")
	(generator_version "10.0")
	(general
		(thickness 1.6)
		(legacy_teardrops no)
	)
	(paper "A4")
	(title_block
		(title "04192023_DAF0TMB3IC0_F0TG_MB_C_brd_V02_OCP.brd")
		(comment 1 "Grand Teton / footprints 3405-3406 of 8354")
	)
	(layers
		(0 "F.Cu" signal "TOP")
		(4 "In1.Cu" signal "GND")
		(6 "In2.Cu" signal "IN1")
		(8 "In3.Cu" signal "GND1")
		(10 "In4.Cu" signal "IN2")
		(12 "In5.Cu" signal "GND2")
		(14 "In6.Cu" signal "IN3")
		(16 "In7.Cu" signal "GND3")
		(18 "In8.Cu" signal "VCC")
		(20 "In9.Cu" signal "VCC1")
		(22 "In10.Cu" signal "GND4")
		(24 "In11.Cu" signal "IN4")
		(26 "In12.Cu" signal "GND5")
		(28 "In13.Cu" signal "IN5")
		(30 "In14.Cu" signal "GND6")
		(32 "In15.Cu" signal "IN6")
		(34 "In16.Cu" signal "GND7")
		(2 "B.Cu" signal "BOTTOM")
		(9 "F.Adhes" user "F.Adhesive")
		(11 "B.Adhes" user "B.Adhesive")
		(13 "F.Paste" user "Package Geometry/Pastemask Top")
		(15 "B.Paste" user "Package Geometry/Pastemask Bottom")
		(5 "F.SilkS" user "Ref Des/Silkscreen Top")
		(7 "B.SilkS" user "Ref Des/Silkscreen Bottom")
		(1 "F.Mask" user "Board Geometry/Soldermask Top")
		(3 "B.Mask" user "Board Geometry/Soldermask Bottom")
		(17 "Dwgs.User" user "User.Drawings")
		(19 "Cmts.User" user "User.Comments")
		(21 "Eco1.User" user "User.Eco1")
		(23 "Eco2.User" user "User.Eco2")
		(25 "Edge.Cuts" user "Board Geometry/Outline")
		(27 "Margin" user)
		(31 "F.CrtYd" user "Package Geometry/Place Bound Top")
		(29 "B.CrtYd" user "Package Geometry/Place Bound Bottom")
		(35 "F.Fab" user "Ref Des/Assembly Top")
		(33 "B.Fab" user "Ref Des/Assembly Bottom")
	)
	(footprint ""
		(layer "F.Cu")
		(at 47.117 -436.372)
		(property "Reference" "U196"
			(at -3.295396 -4.107942 0)
			(unlocked yes)
			(layer "F.SilkS")
			(effects
				(font
					(size 0.7874 0.5842)
					(thickness 0.1524)
				)
				(justify left)
			)
		)
		(property "Value" ""
			(at 0 0 0)
			(layer "F.Fab")
			(effects
				(font
					(size 1.27 1.27)
				)
			)
		)
		(duplicate_pad_numbers_are_jumpers no)
		(fp_line
			(start -1.3462 -1.100074)
			(end -0.670052 -1.100074)
			(stroke
				(width 0.1524)
				(type default)
			)
			(layer "F.SilkS")
		)
		(fp_line
			(start -1.3462 1.100074)
			(end -1.3462 -1.100074)
			(stroke
				(width 0.1524)
				(type default)
			)
			(layer "F.SilkS")
		)
		(fp_line
			(start -0.670052 -1.100074)
			(end 0 -0.381)
			(stroke
				(width 0.1524)
				(type default)
			)
			(layer "F.SilkS")
		)
		(fp_line
			(start 0 -0.381)
			(end 0.670052 -1.100074)
			(stroke
				(width 0.1524)
				(type default)
			)
			(layer "F.SilkS")
		)
		(fp_line
			(start 0.670052 -1.100074)
			(end 1.3462 -1.100074)
			(stroke
				(width 0.1524)
				(type default)
			)
			(layer "F.SilkS")
		)
		(fp_line
			(start 1.3462 -1.100074)
			(end 1.3462 1.100074)
			(stroke
				(width 0.1524)
				(type default)
			)
			(layer "F.SilkS")
		)
		(fp_line
			(start 1.3462 1.100074)
			(end -1.3462 1.100074)
			(stroke
				(width 0.1524)
				(type default)
			)
			(layer "F.SilkS")
		)
		(fp_poly
			(pts
				(xy -2.29108 -1.452372) (xy -1.752346 -1.991106) (xy -1.482852 -1.182878)
			)
			(stroke
				(width 0)
				(type default)
			)
			(fill yes)
			(layer "F.SilkS")
		)
		(fp_line
			(start -1.100074 -0.8001)
			(end -0.670052 -0.8001)
			(stroke
				(width 0.1)
				(type default)
			)
			(layer "F.Fab")
		)
		(fp_line
			(start -1.100074 0.8001)
			(end -1.100074 -0.8001)
			(stroke
				(width 0.1)
				(type default)
			)
			(layer "F.Fab")
		)
		(fp_line
			(start -0.670052 -1.100074)
			(end 0.670052 -1.100074)
			(stroke
				(width 0.1)
				(type default)
			)
			(layer "F.Fab")
		)
		(fp_line
			(start -0.670052 -0.8001)
			(end -0.670052 -1.100074)
			(stroke
				(width 0.1)
				(type default)
			)
			(layer "F.Fab")
		)
		(fp_line
			(start -0.670052 0.8001)
			(end -1.100074 0.8001)
			(stroke
				(width 0.1)
				(type default)
			)
			(layer "F.Fab")
		)
		(fp_line
			(start -0.670052 0.8001)
			(end -0.670052 -0.8001)
			(stroke
				(width 0.1)
				(type default)
			)
			(layer "F.Fab")
		)
		(fp_line
			(start -0.670052 1.100074)
			(end -0.670052 0.8001)
			(stroke
				(width 0.1)
				(type default)
			)
			(layer "F.Fab")
		)
		(fp_line
			(start 0.670052 -1.100074)
			(end 0.670052 -0.8001)
			(stroke
				(width 0.1)
				(type default)
			)
			(layer "F.Fab")
		)
		(fp_line
			(start 0.670052 -0.8001)
			(end 0.670052 0.8001)
			(stroke
				(width 0.1)
				(type default)
			)
			(layer "F.Fab")
		)
		(fp_line
			(start 0.670052 -0.8001)
			(end 1.100074 -0.8001)
			(stroke
				(width 0.1)
				(type default)
			)
			(layer "F.Fab")
		)
		(fp_line
			(start 0.670052 0.8001)
			(end 0.670052 1.100074)
			(stroke
				(width 0.1)
				(type default)
			)
			(layer "F.Fab")
		)
		(fp_line
			(start 0.670052 1.100074)
			(end -0.670052 1.100074)
			(stroke
				(width 0.1)
				(type default)
			)
			(layer "F.Fab")
		)
		(fp_line
			(start 1.100074 -0.8001)
			(end 1.100074 0.8001)
			(stroke
				(width 0.1)
				(type default)
			)
			(layer "F.Fab")
		)
		(fp_line
			(start 1.100074 0.8001)
			(end 0.670052 0.8001)
			(stroke
				(width 0.1)
				(type default)
			)
			(layer "F.Fab")
		)
		(fp_poly
			(pts
				(xy -1.524 -0.649986) (xy -2.286 -1.030986) (xy -2.286 -0.268986)
			)
			(stroke
				(width 0)
				(type default)
			)
			(fill yes)
			(layer "F.Fab")
		)
		(pad "1" smd rect
			(at -0.94996 -0.649986 270)
			(size 0.4064 0.508)
			(layers "F.Cu" "F.Mask" "F.Paste")
			(net "FM_GPU_PWR_EN_R")
		)
		(pad "2" smd rect
			(at -0.94996 0 270)
			(size 0.4064 0.508)
			(layers "F.Cu" "F.Mask" "F.Paste")
			(net "GND")
		)
		(pad "3" smd rect
			(at -0.94996 0.649986 270)
			(size 0.4064 0.508)
			(layers "F.Cu" "F.Mask" "F.Paste")
			(net "GPU_FPGA_RST_R_N")
		)
		(pad "4" smd rect
			(at 0.94996 0.649986 270)
			(size 0.4064 0.508)
			(layers "F.Cu" "F.Mask" "F.Paste")
			(net "GPU_FPGA_RST_R1_BUF_N")
		)
		(pad "5" smd rect
			(at 0.94996 0 270)
			(size 0.4064 0.508)
			(layers "F.Cu" "F.Mask" "F.Paste")
			(net "P3V3_AUX")
		)
		(pad "6" smd rect
			(at 0.94996 -0.649986 270)
			(size 0.4064 0.508)
			(layers "F.Cu" "F.Mask" "F.Paste")
			(net "FM_GPU_PWR_EN_R1")
		)
	)
	(footprint ""
		(layer "F.Cu")
		(at 316.738 -356.87 90)
		(property "Reference" "PR69"
			(at 0 0 90)
			(layer "F.SilkS")
			(hide yes)
			(effects
				(font
					(size 1.27 1.27)
				)
			)
		)
		(property "Value" ""
			(at 0 0 90)
			(layer "F.Fab")
			(effects
				(font
					(size 1.27 1.27)
				)
			)
		)
		(duplicate_pad_numbers_are_jumpers no)
		(fp_line
			(start 0.7874 -0.4064)
			(end 0.7874 0.4064)
			(stroke
				(width 0.1524)
				(type default)
			)
			(layer "F.SilkS")
		)
		(fp_line
			(start -0.7874 -0.4064)
			(end 0.7874 -0.4064)
			(stroke
				(width 0.1524)
				(type default)
			)
			(layer "F.SilkS")
		)
		(fp_line
			(start 0.7874 0.4064)
			(end -0.7874 0.4064)
			(stroke
				(width 0.1524)
				(type default)
			)
			(layer "F.SilkS")
		)
		(fp_line
			(start -0.7874 0.4064)
			(end -0.7874 -0.4064)
			(stroke
				(width 0.1524)
				(type default)
			)
			(layer "F.SilkS")
		)
		(fp_line
			(start -0.12065 -0.305054)
			(end -0.12065 -0.2794)
			(stroke
				(width 0.1)
				(type default)
			)
			(layer "F.Fab")
		)
		(fp_line
			(start -0.67945 -0.305054)
			(end -0.12065 -0.305054)
			(stroke
				(width 0.1)
				(type default)
			)
			(layer "F.Fab")
		)
		(fp_line
			(start 0.67945 -0.3048)
			(end 0.67945 0.3048)
			(stroke
				(width 0.1)
				(type default)
			)
			(layer "F.Fab")
		)
		(fp_line
			(start 0.12065 -0.3048)
			(end 0.67945 -0.3048)
			(stroke
				(width 0.1)
				(type default)
			)
			(layer "F.Fab")
		)
		(fp_line
			(start 0.12065 -0.2794)
			(end 0.12065 -0.3048)
			(stroke
				(width 0.1)
				(type default)
			)
			(layer "F.Fab")
		)
		(fp_line
			(start -0.12065 -0.2794)
			(end 0.12065 -0.2794)
			(stroke
				(width 0.1)
				(type default)
			)
			(layer "F.Fab")
		)
		(fp_line
			(start 0.120396 0.2794)
			(end -0.12065 0.2794)
			(stroke
				(width 0.1)
				(type default)
			)
			(layer "F.Fab")
		)
		(fp_line
			(start -0.12065 0.2794)
			(end -0.12065 0.3048)
			(stroke
				(width 0.1)
				(type default)
			)
			(layer "F.Fab")
		)
		(fp_line
			(start 0.67945 0.3048)
			(end 0.120396 0.3048)
			(stroke
				(width 0.1)
				(type default)
			)
			(layer "F.Fab")
		)
		(fp_line
			(start 0.120396 0.3048)
			(end 0.120396 0.2794)
			(stroke
				(width 0.1)
				(type default)
			)
			(layer "F.Fab")
		)
		(fp_line
			(start -0.12065 0.3048)
			(end -0.67945 0.3048)
			(stroke
				(width 0.1)
				(type default)
			)
			(layer "F.Fab")
		)
		(fp_line
			(start -0.67945 0.3048)
			(end -0.67945 -0.305054)
			(stroke
				(width 0.1)
				(type default)
			)
			(layer "F.Fab")
		)
		(pad "1" smd circle
			(at -0.40005 0 90)
			(size 0 0)
			(layers "F.Cu" "F.Mask" "F.Paste")
			(net "VSENSE_PVDDIO_P0_DP")
		)
		(pad "2" smd circle
			(at 0.40005 0 90)
			(size 0 0)
			(layers "F.Cu" "F.Mask" "F.Paste")
			(net "VSENSE_PVDDIO_P0_VSEN1")
		)
	)
)
